(kicad_pcb
	(version 20221018)
	(generator pcbnew)
	(general
    (thickness 1.62)
  )
	(paper "A4")
	(title_block
    (title "ECP5 - Datacenter Secure Control Module (DC-SCM)")
    (date "2024-07-01")
    (rev "1.2.1")
		(comment 9 "footprint 36 of 506 (U10), pads 1-96 of 96")
	)
	(layers
    (0 "F.Cu" signal)
    (1 "In1.Cu" power)
    (2 "In2.Cu" signal)
    (3 "In3.Cu" power)
    (4 "In4.Cu" power)
    (5 "In5.Cu" signal)
    (6 "In6.Cu" power)
    (31 "B.Cu" signal)
    (32 "B.Adhes" user "B.Adhesive")
    (33 "F.Adhes" user "F.Adhesive")
    (34 "B.Paste" user)
    (35 "F.Paste" user)
    (36 "B.SilkS" user "B.Silkscreen")
    (37 "F.SilkS" user "F.Silkscreen")
    (38 "B.Mask" user)
    (39 "F.Mask" user)
    (40 "Dwgs.User" user "User.Drawings")
    (41 "Cmts.User" user "User.Comments")
    (42 "Eco1.User" user "User.Eco1")
    (43 "Eco2.User" user "User.Eco2")
    (44 "Edge.Cuts" user)
    (45 "Margin" user)
    (46 "B.CrtYd" user "B.Courtyard")
    (47 "F.CrtYd" user "F.Courtyard")
    (48 "B.Fab" user)
    (49 "F.Fab" user)
  )
	(footprint "antmicro-footprints:BGA-96_9.0x13.0mm_Layout2x3x16_P0.8mm" locked
    (layer "F.Cu")
    (at 83.5 123.35 180)
    (descr "BGA-96, http://www.mouser.com/ds/2/198/43-46TR16640B-81280BL-706483.pdf")
    (tags "BGA-96")
    (property "Author" "Antmicro")
    (property "License" "Apache-2.0")
    (property "MPN" "AS4C256M16D3")
    (property "Manufacturer" "Alliance Memory")
    (property "Sheetfile" "ddr3.kicad_sch")
    (property "Sheetname" "DDR3")
    (property "ki_description" "SDRAM - DDR3 Memory IC 4Gbit Parallel 800 MHz 20 ns 96-FBGA (9x13)")
    (property "ki_keywords" "SMT, MEMORY, IC, DDR, SYNCHRONOUS")
    (attr smd)
    (fp_text reference "U10" (at 3.41 7.225) (layer "F.SilkS")
        (effects (font (size 0.7 0.7) (thickness 0.127)))
    )
    (fp_text value "AS4C256M16D3" (at 0 7.5) (layer "F.Fab")
        (effects (font (size 1 1) (thickness 0.15)))
    )
    (pad "A1" smd circle locked (at -3.202 -6 180) (size 0.4 0.4) (layers "F.Cu" "F.Paste" "F.Mask")
      (net 3 "VCC1V35") (pinfunction "VDDQ") (pintype "power_in"))
    (pad "A2" smd circle locked (at -2.4 -6 180) (size 0.4 0.4) (layers "F.Cu" "F.Paste" "F.Mask")
      (net 180 "DDR3_DQ13") (pinfunction "DQ13") (pintype "bidirectional"))
    (pad "A3" smd circle locked (at -1.601 -6 180) (size 0.4 0.4) (layers "F.Cu" "F.Paste" "F.Mask")
      (net 179 "DDR3_DQ15") (pinfunction "DQ15") (pintype "bidirectional"))
    (pad "A7" smd circle locked (at 1.6 -6 180) (size 0.4 0.4) (layers "F.Cu" "F.Paste" "F.Mask")
      (net 185 "DDR3_DQ12") (pinfunction "DQ12") (pintype "bidirectional"))
    (pad "A8" smd circle locked (at 2.398 -6 180) (size 0.4 0.4) (layers "F.Cu" "F.Paste" "F.Mask")
      (net 3 "VCC1V35") (pinfunction "VDDQ") (pintype "passive"))
    (pad "A9" smd circle locked (at 3.2 -6 180) (size 0.4 0.4) (layers "F.Cu" "F.Paste" "F.Mask")
      (net 1 "GND") (pinfunction "VSS") (pintype "power_in"))
    (pad "B1" smd circle locked (at -3.202 -5.202 180) (size 0.4 0.4) (layers "F.Cu" "F.Paste" "F.Mask")
      (net 1 "GND") (pinfunction "VSSQ") (pintype "power_in"))
    (pad "B2" smd circle locked (at -2.4 -5.202 180) (size 0.4 0.4) (layers "F.Cu" "F.Paste" "F.Mask")
      (net 3 "VCC1V35") (pinfunction "VDD") (pintype "power_in"))
    (pad "B3" smd circle locked (at -1.601 -5.202 180) (size 0.4 0.4) (layers "F.Cu" "F.Paste" "F.Mask")
      (net 1 "GND") (pinfunction "VSS") (pintype "passive"))
    (pad "B7" smd circle locked (at 1.6 -5.202 180) (size 0.4 0.4) (layers "F.Cu" "F.Paste" "F.Mask")
      (net 176 "DDR3_DQS1-") (pinfunction "~{UDQS}") (pintype "bidirectional"))
    (pad "B8" smd circle locked (at 2.398 -5.202 180) (size 0.4 0.4) (layers "F.Cu" "F.Paste" "F.Mask")
      (net 181 "DDR3_DQ14") (pinfunction "DQ14") (pintype "bidirectional"))
    (pad "B9" smd circle locked (at 3.2 -5.202 180) (size 0.4 0.4) (layers "F.Cu" "F.Paste" "F.Mask")
      (net 1 "GND") (pinfunction "VSSQ") (pintype "passive"))
    (pad "C1" smd circle locked (at -3.202 -4.401 180) (size 0.4 0.4) (layers "F.Cu" "F.Paste" "F.Mask")
      (net 3 "VCC1V35") (pinfunction "VDDQ") (pintype "passive"))
    (pad "C2" smd circle locked (at -2.4 -4.401 180) (size 0.4 0.4) (layers "F.Cu" "F.Paste" "F.Mask")
      (net 187 "DDR3_DQ11") (pinfunction "DQ11") (pintype "bidirectional"))
    (pad "C3" smd circle locked (at -1.601 -4.401 180) (size 0.4 0.4) (layers "F.Cu" "F.Paste" "F.Mask")
      (net 182 "DDR3_DQ9") (pinfunction "DQ9") (pintype "bidirectional"))
    (pad "C7" smd circle locked (at 1.6 -4.401 180) (size 0.4 0.4) (layers "F.Cu" "F.Paste" "F.Mask")
      (net 175 "DDR3_DQS1+") (pinfunction "UDQS") (pintype "bidirectional"))
    (pad "C8" smd circle locked (at 2.398 -4.401 180) (size 0.4 0.4) (layers "F.Cu" "F.Paste" "F.Mask")
      (net 186 "DDR3_DQ10") (pinfunction "DQ10") (pintype "bidirectional"))
    (pad "C9" smd circle locked (at 3.2 -4.401 180) (size 0.4 0.4) (layers "F.Cu" "F.Paste" "F.Mask")
      (net 3 "VCC1V35") (pinfunction "VDDQ") (pintype "passive"))
    (pad "D1" smd circle locked (at -3.202 -3.601 180) (size 0.4 0.4) (layers "F.Cu" "F.Paste" "F.Mask")
      (net 1 "GND") (pinfunction "VSSQ") (pintype "passive"))
    (pad "D2" smd circle locked (at -2.4 -3.601 180) (size 0.4 0.4) (layers "F.Cu" "F.Paste" "F.Mask")
      (net 3 "VCC1V35") (pinfunction "VDDQ") (pintype "passive"))
    (pad "D3" smd circle locked (at -1.601 -3.601 180) (size 0.4 0.4) (layers "F.Cu" "F.Paste" "F.Mask")
      (net 184 "DDR3_DM1") (pinfunction "UDM") (pintype "input"))
    (pad "D7" smd circle locked (at 1.6 -3.601 180) (size 0.4 0.4) (layers "F.Cu" "F.Paste" "F.Mask")
      (net 195 "DDR3_DQ8") (pinfunction "DQ8") (pintype "bidirectional"))
    (pad "D8" smd circle locked (at 2.398 -3.601 180) (size 0.4 0.4) (layers "F.Cu" "F.Paste" "F.Mask")
      (net 1 "GND") (pinfunction "VSSQ") (pintype "passive"))
    (pad "D9" smd circle locked (at 3.2 -3.601 180) (size 0.4 0.4) (layers "F.Cu" "F.Paste" "F.Mask")
      (net 3 "VCC1V35") (pinfunction "VDD") (pintype "passive"))
    (pad "E1" smd circle locked (at -3.202 -2.801 180) (size 0.4 0.4) (layers "F.Cu" "F.Paste" "F.Mask")
      (net 1 "GND") (pinfunction "VSS") (pintype "passive"))
    (pad "E2" smd circle locked (at -2.4 -2.801 180) (size 0.4 0.4) (layers "F.Cu" "F.Paste" "F.Mask")
      (net 1 "GND") (pinfunction "VSSQ") (pintype "passive"))
    (pad "E3" smd circle locked (at -1.601 -2.801 180) (size 0.4 0.4) (layers "F.Cu" "F.Paste" "F.Mask")
      (net 196 "DDR3_DQ0") (pinfunction "DQ0") (pintype "bidirectional"))
    (pad "E7" smd circle locked (at 1.6 -2.801 180) (size 0.4 0.4) (layers "F.Cu" "F.Paste" "F.Mask")
      (net 178 "DDR3_DM0") (pinfunction "LDM") (pintype "input"))
    (pad "E8" smd circle locked (at 2.398 -2.801 180) (size 0.4 0.4) (layers "F.Cu" "F.Paste" "F.Mask")
      (net 1 "GND") (pinfunction "VSSQ") (pintype "passive"))
    (pad "E9" smd circle locked (at 3.2 -2.801 180) (size 0.4 0.4) (layers "F.Cu" "F.Paste" "F.Mask")
      (net 3 "VCC1V35") (pinfunction "VDDQ") (pintype "passive"))
    (pad "F1" smd circle locked (at -3.202 -2 180) (size 0.4 0.4) (layers "F.Cu" "F.Paste" "F.Mask")
      (net 3 "VCC1V35") (pinfunction "VDDQ") (pintype "passive"))
    (pad "F2" smd circle locked (at -2.4 -2 180) (size 0.4 0.4) (layers "F.Cu" "F.Paste" "F.Mask")
      (net 190 "DDR3_DQ2") (pinfunction "DQ2") (pintype "bidirectional"))
    (pad "F3" smd circle locked (at -1.601 -2 180) (size 0.4 0.4) (layers "F.Cu" "F.Paste" "F.Mask")
      (net 183 "DDR3_DQS0+") (pinfunction "LDQS") (pintype "bidirectional"))
    (pad "F7" smd circle locked (at 1.6 -2 180) (size 0.4 0.4) (layers "F.Cu" "F.Paste" "F.Mask")
      (net 191 "DDR3_DQ1") (pinfunction "DQ1") (pintype "bidirectional"))
    (pad "F8" smd circle locked (at 2.398 -2 180) (size 0.4 0.4) (layers "F.Cu" "F.Paste" "F.Mask")
      (net 193 "DDR3_DQ3") (pinfunction "DQ3") (pintype "bidirectional"))
    (pad "F9" smd circle locked (at 3.2 -2 180) (size 0.4 0.4) (layers "F.Cu" "F.Paste" "F.Mask")
      (net 1 "GND") (pinfunction "VSSQ") (pintype "passive"))
    (pad "G1" smd circle locked (at -3.202 -1.2 180) (size 0.4 0.4) (layers "F.Cu" "F.Paste" "F.Mask")
      (net 1 "GND") (pinfunction "VSSQ") (pintype "passive"))
    (pad "G2" smd circle locked (at -2.4 -1.2 180) (size 0.4 0.4) (layers "F.Cu" "F.Paste" "F.Mask")
      (net 194 "DDR3_DQ6") (pinfunction "DQ6") (pintype "bidirectional"))
    (pad "G3" smd circle locked (at -1.601 -1.2 180) (size 0.4 0.4) (layers "F.Cu" "F.Paste" "F.Mask")
      (net 177 "DDR3_DQS0-") (pinfunction "~{LDQS}") (pintype "bidirectional"))
    (pad "G7" smd circle locked (at 1.6 -1.2 180) (size 0.4 0.4) (layers "F.Cu" "F.Paste" "F.Mask")
      (net 3 "VCC1V35") (pinfunction "VDD") (pintype "passive"))
    (pad "G8" smd circle locked (at 2.398 -1.2 180) (size 0.4 0.4) (layers "F.Cu" "F.Paste" "F.Mask")
      (net 1 "GND") (pinfunction "VSS") (pintype "passive"))
    (pad "G9" smd circle locked (at 3.2 -1.2 180) (size 0.4 0.4) (layers "F.Cu" "F.Paste" "F.Mask")
      (net 1 "GND") (pinfunction "VSSQ") (pintype "passive"))
    (pad "H1" smd circle locked (at -3.202 -0.402 180) (size 0.4 0.4) (layers "F.Cu" "F.Paste" "F.Mask")
      (net 217 "DDR3_VREF") (pinfunction "VREF_DQ") (pintype "power_in"))
    (pad "H2" smd circle locked (at -2.4 -0.402 180) (size 0.4 0.4) (layers "F.Cu" "F.Paste" "F.Mask")
      (net 3 "VCC1V35") (pinfunction "VDDQ") (pintype "passive"))
    (pad "H3" smd circle locked (at -1.601 -0.402 180) (size 0.4 0.4) (layers "F.Cu" "F.Paste" "F.Mask")
      (net 192 "DDR3_DQ4") (pinfunction "DQ4") (pintype "bidirectional"))
    (pad "H7" smd circle locked (at 1.6 -0.402 180) (size 0.4 0.4) (layers "F.Cu" "F.Paste" "F.Mask")
      (net 188 "DDR3_DQ7") (pinfunction "DQ7") (pintype "bidirectional"))
    (pad "H8" smd circle locked (at 2.398 -0.402 180) (size 0.4 0.4) (layers "F.Cu" "F.Paste" "F.Mask")
      (net 189 "DDR3_DQ5") (pinfunction "DQ5") (pintype "bidirectional"))
    (pad "H9" smd circle locked (at 3.2 -0.402 180) (size 0.4 0.4) (layers "F.Cu" "F.Paste" "F.Mask")
      (net 3 "VCC1V35") (pinfunction "VDDQ") (pintype "passive"))
    (pad "J1" smd circle locked (at -3.202 0.4 180) (size 0.4 0.4) (layers "F.Cu" "F.Paste" "F.Mask")
      (net 504 "unconnected-(U10-NC{slash}ODT1-PadJ1)") (pinfunction "NC/ODT1") (pintype "passive+no_connect"))
    (pad "J2" smd circle locked (at -2.4 0.4 180) (size 0.4 0.4) (layers "F.Cu" "F.Paste" "F.Mask")
      (net 1 "GND") (pinfunction "VSS") (pintype "passive"))
    (pad "J3" smd circle locked (at -1.601 0.4 180) (size 0.4 0.4) (layers "F.Cu" "F.Paste" "F.Mask")
      (net 258 "DDR3_RAS") (pinfunction "~{RAS}") (pintype "input"))
    (pad "J7" smd circle locked (at 1.6 0.4 180) (size 0.4 0.4) (layers "F.Cu" "F.Paste" "F.Mask")
      (net 261 "DDR3_CLK+") (pinfunction "CK") (pintype "input"))
    (pad "J8" smd circle locked (at 2.398 0.4 180) (size 0.4 0.4) (layers "F.Cu" "F.Paste" "F.Mask")
      (net 1 "GND") (pinfunction "VSS") (pintype "passive"))
    (pad "J9" smd circle locked (at 3.2 0.4 180) (size 0.4 0.4) (layers "F.Cu" "F.Paste" "F.Mask")
      (net 505 "unconnected-(U10-NC{slash}CKE1-PadJ9)") (pinfunction "NC/CKE1") (pintype "passive+no_connect"))
    (pad "K1" smd circle locked (at -3.202 1.199 180) (size 0.4 0.4) (layers "F.Cu" "F.Paste" "F.Mask")
      (net 259 "DDR3_ODT") (pinfunction "ODT") (pintype "input"))
    (pad "K2" smd circle locked (at -2.4 1.199 180) (size 0.4 0.4) (layers "F.Cu" "F.Paste" "F.Mask")
      (net 3 "VCC1V35") (pinfunction "VDD") (pintype "passive"))
    (pad "K3" smd circle locked (at -1.601 1.199 180) (size 0.4 0.4) (layers "F.Cu" "F.Paste" "F.Mask")
      (net 254 "DDR3_CAS") (pinfunction "~{CAS}") (pintype "input"))
    (pad "K7" smd circle locked (at 1.6 1.199 180) (size 0.4 0.4) (layers "F.Cu" "F.Paste" "F.Mask")
      (net 262 "DDR3_CLK-") (pinfunction "~{CK}") (pintype "input"))
    (pad "K8" smd circle locked (at 2.398 1.199 180) (size 0.4 0.4) (layers "F.Cu" "F.Paste" "F.Mask")
      (net 3 "VCC1V35") (pinfunction "VDD") (pintype "passive"))
    (pad "K9" smd circle locked (at 3.2 1.199 180) (size 0.4 0.4) (layers "F.Cu" "F.Paste" "F.Mask")
      (net 260 "DDR3_CKE") (pinfunction "CKE") (pintype "input"))
    (pad "L1" smd circle locked (at -3.202 1.999 180) (size 0.4 0.4) (layers "F.Cu" "F.Paste" "F.Mask")
      (net 506 "unconnected-(U10-NC{slash}~{CS1}-PadL1)") (pinfunction "NC/~{CS1}") (pintype "passive+no_connect"))
    (pad "L2" smd circle locked (at -2.4 1.999 180) (size 0.4 0.4) (layers "F.Cu" "F.Paste" "F.Mask")
      (net 257 "DDR3_CS") (pinfunction "~{CS}") (pintype "input"))
    (pad "L3" smd circle locked (at -1.601 1.999 180) (size 0.4 0.4) (layers "F.Cu" "F.Paste" "F.Mask")
      (net 251 "DDR3_WE") (pinfunction "~{WE}") (pintype "input"))
    (pad "L7" smd circle locked (at 1.6 1.999 180) (size 0.4 0.4) (layers "F.Cu" "F.Paste" "F.Mask")
      (net 250 "DDR3_A10") (pinfunction "A10/AP") (pintype "input"))
    (pad "L8" smd circle locked (at 2.398 1.999 180) (size 0.4 0.4) (layers "F.Cu" "F.Paste" "F.Mask")
      (net 418 "Net-(U10-ZQ)") (pinfunction "ZQ") (pintype "passive"))
    (pad "L9" smd circle locked (at 3.2 1.999 180) (size 0.4 0.4) (layers "F.Cu" "F.Paste" "F.Mask")
      (net 507 "unconnected-(U10-NC{slash}ZQ1-PadL9)") (pinfunction "NC/ZQ1") (pintype "passive+no_connect"))
    (pad "M1" smd circle locked (at -3.202 2.798 180) (size 0.4 0.4) (layers "F.Cu" "F.Paste" "F.Mask")
      (net 1 "GND") (pinfunction "VSS") (pintype "passive"))
    (pad "M2" smd circle locked (at -2.4 2.798 180) (size 0.4 0.4) (layers "F.Cu" "F.Paste" "F.Mask")
      (net 256 "DDR3_BA0") (pinfunction "BA0") (pintype "input"))
    (pad "M3" smd circle locked (at -1.601 2.798 180) (size 0.4 0.4) (layers "F.Cu" "F.Paste" "F.Mask")
      (net 252 "DDR3_BA2") (pinfunction "BA2") (pintype "input"))
    (pad "M7" smd circle locked (at 1.6 2.798 180) (size 0.4 0.4) (layers "F.Cu" "F.Paste" "F.Mask")
      (net 508 "unconnected-(U10-NC{slash}A15-PadM7)") (pinfunction "NC/A15") (pintype "passive+no_connect"))
    (pad "M8" smd circle locked (at 2.398 2.798 180) (size 0.4 0.4) (layers "F.Cu" "F.Paste" "F.Mask")
      (net 217 "DDR3_VREF") (pinfunction "VREF_CA") (pintype "power_in"))
    (pad "M9" smd circle locked (at 3.2 2.798 180) (size 0.4 0.4) (layers "F.Cu" "F.Paste" "F.Mask")
      (net 1 "GND") (pinfunction "VSS") (pintype "passive"))
    (pad "N1" smd circle locked (at -3.202 3.6 180) (size 0.4 0.4) (layers "F.Cu" "F.Paste" "F.Mask")
      (net 3 "VCC1V35") (pinfunction "VDD") (pintype "passive"))
    (pad "N2" smd circle locked (at -2.4 3.6 180) (size 0.4 0.4) (layers "F.Cu" "F.Paste" "F.Mask")
      (net 255 "DDR3_A3") (pinfunction "A3") (pintype "input"))
    (pad "N3" smd circle locked (at -1.601 3.6 180) (size 0.4 0.4) (layers "F.Cu" "F.Paste" "F.Mask")
      (net 246 "DDR3_A0") (pinfunction "A0") (pintype "input"))
    (pad "N7" smd circle locked (at 1.6 3.6 180) (size 0.4 0.4) (layers "F.Cu" "F.Paste" "F.Mask")
      (net 248 "DDR3_A12") (pinfunction "A12/~{BC}") (pintype "input"))
    (pad "N8" smd circle locked (at 2.398 3.6 180) (size 0.4 0.4) (layers "F.Cu" "F.Paste" "F.Mask")
      (net 249 "DDR3_BA1") (pinfunction "BA1") (pintype "input"))
    (pad "N9" smd circle locked (at 3.2 3.6 180) (size 0.4 0.4) (layers "F.Cu" "F.Paste" "F.Mask")
      (net 3 "VCC1V35") (pinfunction "VDD") (pintype "passive"))
    (pad "P1" smd circle locked (at -3.202 4.4 180) (size 0.4 0.4) (layers "F.Cu" "F.Paste" "F.Mask")
      (net 1 "GND") (pinfunction "VSS") (pintype "passive"))
    (pad "P2" smd circle locked (at -2.4 4.4 180) (size 0.4 0.4) (layers "F.Cu" "F.Paste" "F.Mask")
      (net 253 "DDR3_A5") (pinfunction "A5") (pintype "input"))
    (pad "P3" smd circle locked (at -1.601 4.4 180) (size 0.4 0.4) (layers "F.Cu" "F.Paste" "F.Mask")
      (net 241 "DDR3_A2") (pinfunction "A2") (pintype "input"))
    (pad "P7" smd circle locked (at 1.6 4.4 180) (size 0.4 0.4) (layers "F.Cu" "F.Paste" "F.Mask")
      (net 247 "DDR3_A1") (pinfunction "A1") (pintype "input"))
    (pad "P8" smd circle locked (at 2.398 4.4 180) (size 0.4 0.4) (layers "F.Cu" "F.Paste" "F.Mask")
      (net 245 "DDR3_A4") (pinfunction "A4") (pintype "input"))
    (pad "P9" smd circle locked (at 3.2 4.4 180) (size 0.4 0.4) (layers "F.Cu" "F.Paste" "F.Mask")
      (net 1 "GND") (pinfunction "VSS") (pintype "passive"))
    (pad "R1" smd circle locked (at -3.202 5.2 180) (size 0.4 0.4) (layers "F.Cu" "F.Paste" "F.Mask")
      (net 3 "VCC1V35") (pinfunction "VDD") (pintype "passive"))
    (pad "R2" smd circle locked (at -2.4 5.2 180) (size 0.4 0.4) (layers "F.Cu" "F.Paste" "F.Mask")
      (net 240 "DDR3_A7") (pinfunction "A7") (pintype "input"))
    (pad "R3" smd circle locked (at -1.601 5.2 180) (size 0.4 0.4) (layers "F.Cu" "F.Paste" "F.Mask")
      (net 239 "DDR3_A9") (pinfunction "A9") (pintype "input"))
    (pad "R7" smd circle locked (at 1.6 5.2 180) (size 0.4 0.4) (layers "F.Cu" "F.Paste" "F.Mask")
      (net 238 "DDR3_A11") (pinfunction "A11") (pintype "input"))
    (pad "R8" smd circle locked (at 2.398 5.2 180) (size 0.4 0.4) (layers "F.Cu" "F.Paste" "F.Mask")
      (net 242 "DDR3_A6") (pinfunction "A6") (pintype "input"))
    (pad "R9" smd circle locked (at 3.2 5.2 180) (size 0.4 0.4) (layers "F.Cu" "F.Paste" "F.Mask")
      (net 3 "VCC1V35") (pinfunction "VDD") (pintype "passive"))
    (pad "T1" smd circle locked (at -3.202 5.999 180) (size 0.4 0.4) (layers "F.Cu" "F.Paste" "F.Mask")
      (net 1 "GND") (pinfunction "VSS") (pintype "passive"))
    (pad "T2" smd circle locked (at -2.4 5.999 180) (size 0.4 0.4) (layers "F.Cu" "F.Paste" "F.Mask")
      (net 263 "DDR3_RESET") (pinfunction "~{RESET}") (pintype "input"))
    (pad "T3" smd circle locked (at -1.601 5.999 180) (size 0.4 0.4) (layers "F.Cu" "F.Paste" "F.Mask")
      (net 237 "DDR3_A13") (pinfunction "A13") (pintype "input"))
    (pad "T7" smd circle locked (at 1.6 5.999 180) (size 0.4 0.4) (layers "F.Cu" "F.Paste" "F.Mask")
      (net 244 "DDR3_A14") (pinfunction "A14") (pintype "input"))
    (pad "T8" smd circle locked (at 2.398 5.999 180) (size 0.4 0.4) (layers "F.Cu" "F.Paste" "F.Mask")
      (net 243 "DDR3_A8") (pinfunction "A8") (pintype "input"))
    (pad "T9" smd circle locked (at 3.2 5.999 180) (size 0.4 0.4) (layers "F.Cu" "F.Paste" "F.Mask")
      (net 1 "GND") (pinfunction "VSS") (pintype "passive"))
  )
)
